# BASEBOARD_FAB2 (Tioga Pass) — schematic netlist excerpt (pin names and nets, part order shuffled) for the footprints in the layout excerpt that follows; sources: Cadence DE-HDL packaged netlist, KiCad conversion of Wiwynn_Tioga_Pass_MB.brd

C7C3  CAP  0.22UF 16V 10% X7R  pkg 0402  page 129 : A = DMI_CPU0_PCH_TX_DN<0> ; B = DMI_CPU0_PCH_TX_C_DN<0>
R4C10  RES  240 1.0% CHIP  pkg 0402  page 97 : A = PVCCIO_CPU1 ; B = PU_CPU1_TSC_SYNC
CT51  CAP_A  0.1UF 16V 10% X7R  pkg 0402V  page 216 : A = VR_PVDDQ_ABC_AIREF1 ; B = GND

(kicad_pcb
	(version 20260206)
	(generator "pcbnew")
	(generator_version "10.0")
	(general
		(thickness 1.6)
		(legacy_teardrops no)
	)
	(paper "A4")
	(title_block
		(title "Wiwynn_Tioga_Pass_MB.brd")
		(comment 1 "Tioga Pass / footprints 2148-2150 of 4770")
	)
	(layers
		(0 "F.Cu" signal "TOP")
		(4 "In1.Cu" signal "L2GND")
		(6 "In2.Cu" signal "L3")
		(8 "In3.Cu" signal "L4GND")
		(10 "In4.Cu" signal "L5")
		(12 "In5.Cu" signal "L6GND")
		(14 "In6.Cu" signal "L7VCC")
		(16 "In7.Cu" signal "L8VCC")
		(18 "In8.Cu" signal "L9GND")
		(20 "In9.Cu" signal "L10")
		(22 "In10.Cu" signal "L11GND")
		(24 "In11.Cu" signal "L12")
		(26 "In12.Cu" signal "L13GND")
		(2 "B.Cu" signal "BOTTOM")
		(9 "F.Adhes" user "F.Adhesive")
		(11 "B.Adhes" user "B.Adhesive")
		(13 "F.Paste" user "Package Geometry/Pastemask Top")
		(15 "B.Paste" user "Package Geometry/Pastemask Bottom")
		(5 "F.SilkS" user "Ref Des/Silkscreen Top")
		(7 "B.SilkS" user "Ref Des/Silkscreen Bottom")
		(1 "F.Mask" user "Board Geometry/Soldermask Top")
		(3 "B.Mask" user "Board Geometry/Soldermask Bottom")
		(17 "Dwgs.User" user "User.Drawings")
		(19 "Cmts.User" user "User.Comments")
		(21 "Eco1.User" user "User.Eco1")
		(23 "Eco2.User" user "User.Eco2")
		(25 "Edge.Cuts" user "Board Geometry/Outline")
		(27 "Margin" user)
		(31 "F.CrtYd" user "Package Geometry/Place Bound Top")
		(29 "B.CrtYd" user "Package Geometry/Place Bound Bottom")
		(35 "F.Fab" user "Ref Des/Assembly Top")
		(33 "B.Fab" user "Ref Des/Assembly Bottom")
	)
	(footprint ""
		(layer "F.Cu")
		(at 173.297088 -91.22156 -90)
		(property "Reference" "R4C10"
			(at 0 0 270)
			(layer "F.SilkS")
			(hide yes)
			(effects
				(font
					(size 1.27 1.27)
				)
			)
		)
		(property "Value" ""
			(at 0 0 270)
			(layer "F.Fab")
			(effects
				(font
					(size 1.27 1.27)
				)
			)
		)
		(duplicate_pad_numbers_are_jumpers no)
		(fp_poly
			(pts
				(xy -0.2794 -0.1016) (xy 0.2794 -0.1016) (xy 0.2794 0.9906) (xy -0.2794 0.9906)
			)
			(stroke
				(width 0)
				(type default)
			)
			(fill no)
			(layer "F.CrtYd")
		)
		(fp_line
			(start -0.2794 0.9906)
			(end 0.2794 0.9906)
			(stroke
				(width 0.1)
				(type default)
			)
			(layer "F.Fab")
		)
		(fp_line
			(start 0.2794 0.9906)
			(end 0.2794 -0.1016)
			(stroke
				(width 0.1)
				(type default)
			)
			(layer "F.Fab")
		)
		(fp_line
			(start -0.2794 -0.1016)
			(end -0.2794 0.9906)
			(stroke
				(width 0.1)
				(type default)
			)
			(layer "F.Fab")
		)
		(fp_line
			(start 0.2794 -0.1016)
			(end -0.2794 -0.1016)
			(stroke
				(width 0.1)
				(type default)
			)
			(layer "F.Fab")
		)
		(pad "1" smd rect
			(at 0 0 270)
			(size 0.508 0.508)
			(layers "F.Cu" "F.Mask" "F.Paste")
			(net "PVCCIO_CPU1")
		)
		(pad "2" smd rect
			(at 0 0.889 270)
			(size 0.508 0.508)
			(layers "F.Cu" "F.Mask" "F.Paste")
			(net "PU_CPU1_TSC_SYNC")
		)
		(zone
			(layer "F.Cu")
			(hatch none 0.5)
			(connect_pads
				(clearance 0)
			)
			(min_thickness 0.25)
			(keepout
				(tracks not_allowed)
				(vias allowed)
				(pads allowed)
				(copperpour not_allowed)
				(footprints allowed)
			)
			(placement
				(enabled no)
				(sheetname "")
			)
			(fill
				(thermal_gap 0.5)
				(thermal_bridge_width 0.5)
				(island_removal_mode 0)
			)
			(polygon
				(pts
					(xy 172.662088 -91.47556) (xy 172.662088 -90.96756) (xy 173.043088 -90.96756) (xy 173.043088 -91.47556)
				)
			)
		)
		(zone
			(layer "F.Cu")
			(hatch none 0.5)
			(connect_pads
				(clearance 0)
			)
			(min_thickness 0.25)
			(keepout
				(tracks allowed)
				(vias not_allowed)
				(pads allowed)
				(copperpour not_allowed)
				(footprints allowed)
			)
			(placement
				(enabled no)
				(sheetname "")
			)
			(fill
				(thermal_gap 0.5)
				(thermal_bridge_width 0.5)
				(island_removal_mode 0)
			)
			(polygon
				(pts
					(xy 173.043088 -91.47556) (xy 173.043088 -90.96756) (xy 172.662088 -90.96756) (xy 172.662088 -91.47556)
				)
			)
		)
	)
	(footprint ""
		(layer "F.Cu")
		(at 368.554 -109.601 90)
		(property "Reference" "C7C3"
			(at 0 0 90)
			(layer "F.SilkS")
			(hide yes)
			(effects
				(font
					(size 1.27 1.27)
				)
			)
		)
		(property "Value" ""
			(at 0 0 90)
			(layer "F.Fab")
			(effects
				(font
					(size 1.27 1.27)
				)
			)
		)
		(duplicate_pad_numbers_are_jumpers no)
		(fp_poly
			(pts
				(xy 0.3048 -0.1016) (xy 0.3048 0.9906) (xy -0.3048 0.9906) (xy -0.3048 -0.1016)
			)
			(stroke
				(width 0)
				(type default)
			)
			(fill no)
			(layer "F.CrtYd")
		)
		(fp_line
			(start 0.3048 -0.1016)
			(end -0.3048 -0.1016)
			(stroke
				(width 0.1)
				(type default)
			)
			(layer "F.Fab")
		)
		(fp_line
			(start -0.3048 -0.1016)
			(end -0.3048 0.9906)
			(stroke
				(width 0.1)
				(type default)
			)
			(layer "F.Fab")
		)
		(fp_line
			(start 0.3048 0.9906)
			(end 0.3048 -0.1016)
			(stroke
				(width 0.1)
				(type default)
			)
			(layer "F.Fab")
		)
		(fp_line
			(start -0.3048 0.9906)
			(end 0.3048 0.9906)
			(stroke
				(width 0.1)
				(type default)
			)
			(layer "F.Fab")
		)
		(pad "1" smd rect
			(at 0 0 90)
			(size 0.508 0.508)
			(layers "F.Cu" "F.Mask" "F.Paste")
			(net "DMI_CPU0_PCH_TX_DN<0>")
		)
		(pad "2" smd rect
			(at 0 0.889 90)
			(size 0.508 0.508)
			(layers "F.Cu" "F.Mask" "F.Paste")
			(net "DMI_CPU0_PCH_TX_C_DN<0>")
		)
		(zone
			(layer "F.Cu")
			(hatch none 0.5)
			(connect_pads
				(clearance 0)
			)
			(min_thickness 0.25)
			(keepout
				(tracks allowed)
				(vias not_allowed)
				(pads allowed)
				(copperpour not_allowed)
				(footprints allowed)
			)
			(placement
				(enabled no)
				(sheetname "")
			)
			(fill
				(thermal_gap 0.5)
				(thermal_bridge_width 0.5)
				(island_removal_mode 0)
			)
			(polygon
				(pts
					(xy 368.808 -109.347) (xy 368.808 -109.855) (xy 369.189 -109.855) (xy 369.189 -109.347)
				)
			)
		)
		(zone
			(layer "F.Cu")
			(hatch none 0.5)
			(connect_pads
				(clearance 0)
			)
			(min_thickness 0.25)
			(keepout
				(tracks not_allowed)
				(vias allowed)
				(pads allowed)
				(copperpour not_allowed)
				(footprints allowed)
			)
			(placement
				(enabled no)
				(sheetname "")
			)
			(fill
				(thermal_gap 0.5)
				(thermal_bridge_width 0.5)
				(island_removal_mode 0)
			)
			(polygon
				(pts
					(xy 369.189 -109.347) (xy 369.189 -109.855) (xy 368.808 -109.855) (xy 368.808 -109.347)
				)
			)
		)
	)
	(footprint ""
		(layer "F.Cu")
		(at 349.07728 -11.14933 -90)
		(property "Reference" "CT51"
			(at -1.72593 0.0508 0)
			(unlocked yes)
			(layer "F.SilkS")
			(effects
				(font
					(size 0.7874 0.5842)
					(thickness 0.1524)
				)
				(justify left)
			)
		)
		(property "Value" ""
			(at 0 0 270)
			(layer "F.Fab")
			(effects
				(font
					(size 1.27 1.27)
				)
			)
		)
		(duplicate_pad_numbers_are_jumpers no)
		(fp_poly
			(pts
				(xy 0.3048 -0.1016) (xy 0.3048 0.9906) (xy -0.3048 0.9906) (xy -0.3048 -0.1016)
			)
			(stroke
				(width 0)
				(type default)
			)
			(fill no)
			(layer "F.CrtYd")
		)
		(fp_line
			(start -0.3048 0.9906)
			(end 0.3048 0.9906)
			(stroke
				(width 0.1)
				(type default)
			)
			(layer "F.Fab")
		)
		(fp_line
			(start 0.3048 0.9906)
			(end 0.3048 -0.1016)
			(stroke
				(width 0.1)
				(type default)
			)
			(layer "F.Fab")
		)
		(fp_line
			(start -0.3048 -0.1016)
			(end -0.3048 0.9906)
			(stroke
				(width 0.1)
				(type default)
			)
			(layer "F.Fab")
		)
		(fp_line
			(start 0.3048 -0.1016)
			(end -0.3048 -0.1016)
			(stroke
				(width 0.1)
				(type default)
			)
			(layer "F.Fab")
		)
		(pad "1" smd rect
			(at 0 0 270)
			(size 0.508 0.508)
			(layers "F.Cu" "F.Mask" "F.Paste")
			(net "VR_PVDDQ_ABC_AIREF1")
		)
		(pad "2" smd rect
			(at 0 0.889 270)
			(size 0.508 0.508)
			(layers "F.Cu" "F.Mask" "F.Paste")
			(net "GND")
		)
		(zone
			(layer "F.Cu")
			(hatch none 0.5)
			(connect_pads
				(clearance 0)
			)
			(min_thickness 0.25)
			(keepout
				(tracks not_allowed)
				(vias allowed)
				(pads allowed)
				(copperpour not_allowed)
				(footprints allowed)
			)
			(placement
				(enabled no)
				(sheetname "")
			)
			(fill
				(thermal_gap 0.5)
				(thermal_bridge_width 0.5)
				(island_removal_mode 0)
			)
			(polygon
				(pts
					(xy 348.44228 -11.40333) (xy 348.44228 -10.89533) (xy 348.82328 -10.89533) (xy 348.82328 -11.40333)
				)
			)
		)
		(zone
			(layer "F.Cu")
			(hatch none 0.5)
			(connect_pads
				(clearance 0)
			)
			(min_thickness 0.25)
			(keepout
				(tracks allowed)
				(vias not_allowed)
				(pads allowed)
				(copperpour not_allowed)
				(footprints allowed)
			)
			(placement
				(enabled no)
				(sheetname "")
			)
			(fill
				(thermal_gap 0.5)
				(thermal_bridge_width 0.5)
				(island_removal_mode 0)
			)
			(polygon
				(pts
					(xy 348.82328 -11.40333) (xy 348.82328 -10.89533) (xy 348.44228 -10.89533) (xy 348.44228 -11.40333)
				)
			)
		)
	)
)
